# T6G (Grand Teton) — schematic netlist excerpt (pin names and nets, part order shuffled) for the footprints in the layout excerpt that follows; sources: Cadence DE-HDL packaged netlist, KiCad conversion of 04192023_DAF0TMB3IC0_F0TG_MB_C_brd_V02_OCP.brd

PU34  RAA229620GNPHA0  RAA229620GNP#HA0 IC  pkg QFN48_TH_0-4_6X6XH  page 217
  PWM0  = PVDDIO_P1_PWM1
  PWM1  = PVDDIO_P1_PWM2
  PWM2  = PVDDIO_P1_PWM3
  PWM3  = PVDDIO_P1_PWM4
  PWM4  = NC_PVDDCR_CPU1_P1_PWM8
  PWM5  = NC_PVDDCR_CPU1_P1_PWM7
  PWM6  = PVDDCR_CPU1_P1_PWM6
  PWM7  = PVDDCR_CPU1_P1_PWM5
  PWM8  = PVDDCR_CPU1_P1_PWM4
  PWM9  = PVDDCR_CPU1_P1_PWM3
  PWM10  = PVDDCR_CPU1_P1_PWM2
  PWM11  = PVDDCR_CPU1_P1_PWM1
  PMSDA  = SMB_DIO_PVDDCR_CPU1_P1_R
  PMSCL  = SMB_CLK_PVDDCR_CPU1_P1_R
  NPMALERT  = PVDDCR_CPU1_P1_SMB_ALERT_R
  PG0  = PWRGD_PVDDCR_CPU1_P1_R
  EN0  = PVDDCR_CPU1_P1_EN_R
  RESET_L  = PVDDCR_CPU1_P1_RESET_N_R
  VDDIO  = PVDD18_S5_P1
  PG1  = PWRGD_PVDDIO_P1_R
  SVD  = SVID_PVDDCR_CPU1_P1_SVD_R1
  SVC  = SVID_PVDDCR_CPU1_P1_SVC_R1
  SVTO  = SVID_PVDDCR_CPU1_P1_SVTO_R
  SVTI  = SVID_PVDDCR_CPU1_P1_SVTI_R
  VSEN0  = VSENSE_PVDDCR_CPU1_P1_VSEN0
  RGND0  = VSENSE_VSS_SENSE_C_P1
  CS11  = PVDDCR_CPU1_P1_IMON1
  CS10  = PVDDCR_CPU1_P1_IMON2
  CS9  = PVDDCR_CPU1_P1_IMON3
  CS8  = PVDDCR_CPU1_P1_IMON4
  CS7  = PVDDCR_CPU1_P1_IMON5
  CS6  = PVDDCR_CPU1_P1_IMON6
  CS5  = NC_PVDDCR_CPU1_P1_IMON7
  CS4  = NC_PVDDCR_CPU1_P1_IMON8
  CS3  = PVDDIO_P1_IMON4
  CS2  = PVDDIO_P1_IMON3
  CS1  = PVDDIO_P1_IMON2
  CS0  = PVDDIO_P1_IMON1
  RGND1  = VSENSE_VSS_SENSE_B_P1
  VSEN1  = VSENSE_PVDDIO_P1_VSEN1
  OCP_L  = PVDDCR_CPU1_P1_OCP_N_R
  \en1||addr_cfg\  = PVDDCR_CPU1_P1_EN1_ADDR_CFG
  TEMP1  = PVDDIO_P1_TEMP1
  TEMP0  = PVDDCR_CPU1_P1_TEMP0
  \vmon||iinsen\  = PVDDCR_CPU1_P1_VMON
  VINSEN  = PVDDCR_CPU1_P1_VINSEN
  VCC  = PVDDCR_CPU1_P1_VCC
  VCCS  = PVDDCR_CPU1_P1_VCCS
  TH_GND  = GND

(kicad_pcb
	(version 20260206)
	(generator "pcbnew")
	(generator_version "10.0")
	(general
		(thickness 1.6)
		(legacy_teardrops no)
	)
	(paper "A4")
	(title_block
		(title "04192023_DAF0TMB3IC0_F0TG_MB_C_brd_V02_OCP.brd")
		(comment 1 "Grand Teton / footprint 1342 of 8354 (PU34), pads 1-42 of 49")
	)
	(layers
		(0 "F.Cu" signal "TOP")
		(4 "In1.Cu" signal "GND")
		(6 "In2.Cu" signal "IN1")
		(8 "In3.Cu" signal "GND1")
		(10 "In4.Cu" signal "IN2")
		(12 "In5.Cu" signal "GND2")
		(14 "In6.Cu" signal "IN3")
		(16 "In7.Cu" signal "GND3")
		(18 "In8.Cu" signal "VCC")
		(20 "In9.Cu" signal "VCC1")
		(22 "In10.Cu" signal "GND4")
		(24 "In11.Cu" signal "IN4")
		(26 "In12.Cu" signal "GND5")
		(28 "In13.Cu" signal "IN5")
		(30 "In14.Cu" signal "GND6")
		(32 "In15.Cu" signal "IN6")
		(34 "In16.Cu" signal "GND7")
		(2 "B.Cu" signal "BOTTOM")
		(9 "F.Adhes" user "F.Adhesive")
		(11 "B.Adhes" user "B.Adhesive")
		(13 "F.Paste" user "Package Geometry/Pastemask Top")
		(15 "B.Paste" user "Package Geometry/Pastemask Bottom")
		(5 "F.SilkS" user "Ref Des/Silkscreen Top")
		(7 "B.SilkS" user "Ref Des/Silkscreen Bottom")
		(1 "F.Mask" user "Board Geometry/Soldermask Top")
		(3 "B.Mask" user "Board Geometry/Soldermask Bottom")
		(17 "Dwgs.User" user "User.Drawings")
		(19 "Cmts.User" user "User.Comments")
		(21 "Eco1.User" user "User.Eco1")
		(23 "Eco2.User" user "User.Eco2")
		(25 "Edge.Cuts" user "Board Geometry/Outline")
		(27 "Margin" user)
		(31 "F.CrtYd" user "Package Geometry/Place Bound Top")
		(29 "B.CrtYd" user "Package Geometry/Place Bound Bottom")
		(35 "F.Fab" user "Ref Des/Assembly Top")
		(33 "B.Fab" user "Ref Des/Assembly Bottom")
	)
	(footprint ""
		(layer "F.Cu")
		(at 30.48 -364.109 -90)
		(property "Reference" "PU34"
			(at 3.80873 0.935736 0)
			(unlocked yes)
			(layer "F.SilkS")
			(effects
				(font
					(size 0.7874 0.5842)
					(thickness 0.1524)
				)
			)
		)
		(property "Value" ""
			(at 0 0 270)
			(layer "F.Fab")
			(effects
				(font
					(size 1.27 1.27)
				)
			)
		)
		(duplicate_pad_numbers_are_jumpers no)
		(pad "1" smd rect
			(at -2.875026 -2.199894 180)
			(size 0.1778 0.6604)
			(layers "F.Cu" "F.Mask" "F.Paste")
			(net "PVDDIO_P1_PWM1")
		)
		(pad "2" smd rect
			(at -2.875026 -1.800098 180)
			(size 0.1778 0.6604)
			(layers "F.Cu" "F.Mask" "F.Paste")
			(net "PVDDIO_P1_PWM2")
		)
		(pad "3" smd rect
			(at -2.875026 -1.400048 180)
			(size 0.1778 0.6604)
			(layers "F.Cu" "F.Mask" "F.Paste")
			(net "PVDDIO_P1_PWM3")
		)
		(pad "4" smd rect
			(at -2.875026 -0.999998 180)
			(size 0.1778 0.6604)
			(layers "F.Cu" "F.Mask" "F.Paste")
			(net "PVDDIO_P1_PWM4")
		)
		(pad "5" smd rect
			(at -2.875026 -0.599948 180)
			(size 0.1778 0.6604)
			(layers "F.Cu" "F.Mask" "F.Paste")
			(net "NC_PVDDCR_CPU1_P1_PWM8")
		)
		(pad "6" smd rect
			(at -2.875026 -0.199898 180)
			(size 0.1778 0.6604)
			(layers "F.Cu" "F.Mask" "F.Paste")
			(net "NC_PVDDCR_CPU1_P1_PWM7")
		)
		(pad "7" smd rect
			(at -2.875026 0.199898 180)
			(size 0.1778 0.6604)
			(layers "F.Cu" "F.Mask" "F.Paste")
			(net "PVDDCR_CPU1_P1_PWM6")
		)
		(pad "8" smd rect
			(at -2.875026 0.599948 180)
			(size 0.1778 0.6604)
			(layers "F.Cu" "F.Mask" "F.Paste")
			(net "PVDDCR_CPU1_P1_PWM5")
		)
		(pad "9" smd rect
			(at -2.875026 0.999998 180)
			(size 0.1778 0.6604)
			(layers "F.Cu" "F.Mask" "F.Paste")
			(net "PVDDCR_CPU1_P1_PWM4")
		)
		(pad "10" smd rect
			(at -2.875026 1.400048 180)
			(size 0.1778 0.6604)
			(layers "F.Cu" "F.Mask" "F.Paste")
			(net "PVDDCR_CPU1_P1_PWM3")
		)
		(pad "11" smd rect
			(at -2.875026 1.800098 180)
			(size 0.1778 0.6604)
			(layers "F.Cu" "F.Mask" "F.Paste")
			(net "PVDDCR_CPU1_P1_PWM2")
		)
		(pad "12" smd rect
			(at -2.875026 2.199894 180)
			(size 0.1778 0.6604)
			(layers "F.Cu" "F.Mask" "F.Paste")
			(net "PVDDCR_CPU1_P1_PWM1")
		)
		(pad "13" smd rect
			(at -2.199894 2.875026 270)
			(size 0.1778 0.6604)
			(layers "F.Cu" "F.Mask" "F.Paste")
			(net "SMB_DIO_PVDDCR_CPU1_P1_R")
		)
		(pad "14" smd rect
			(at -1.800098 2.875026 270)
			(size 0.1778 0.6604)
			(layers "F.Cu" "F.Mask" "F.Paste")
			(net "SMB_CLK_PVDDCR_CPU1_P1_R")
		)
		(pad "15" smd rect
			(at -1.400048 2.875026 270)
			(size 0.1778 0.6604)
			(layers "F.Cu" "F.Mask" "F.Paste")
			(net "PVDDCR_CPU1_P1_SMB_ALERT_R")
		)
		(pad "16" smd rect
			(at -0.999998 2.875026 270)
			(size 0.1778 0.6604)
			(layers "F.Cu" "F.Mask" "F.Paste")
			(net "PWRGD_PVDDCR_CPU1_P1_R")
		)
		(pad "17" smd rect
			(at -0.599948 2.875026 270)
			(size 0.1778 0.6604)
			(layers "F.Cu" "F.Mask" "F.Paste")
			(net "PVDDCR_CPU1_P1_EN_R")
		)
		(pad "18" smd rect
			(at -0.199898 2.875026 270)
			(size 0.1778 0.6604)
			(layers "F.Cu" "F.Mask" "F.Paste")
			(net "PVDDCR_CPU1_P1_RESET_N_R")
		)
		(pad "19" smd rect
			(at 0.199898 2.875026 270)
			(size 0.1778 0.6604)
			(layers "F.Cu" "F.Mask" "F.Paste")
			(net "PVDD18_S5_P1")
		)
		(pad "20" smd rect
			(at 0.599948 2.875026 270)
			(size 0.1778 0.6604)
			(layers "F.Cu" "F.Mask" "F.Paste")
			(net "PWRGD_PVDDIO_P1_R")
		)
		(pad "21" smd rect
			(at 0.999998 2.875026 270)
			(size 0.1778 0.6604)
			(layers "F.Cu" "F.Mask" "F.Paste")
			(net "SVID_PVDDCR_CPU1_P1_SVD_R1")
		)
		(pad "22" smd rect
			(at 1.400048 2.875026 270)
			(size 0.1778 0.6604)
			(layers "F.Cu" "F.Mask" "F.Paste")
			(net "SVID_PVDDCR_CPU1_P1_SVC_R1")
		)
		(pad "23" smd rect
			(at 1.800098 2.875026 270)
			(size 0.1778 0.6604)
			(layers "F.Cu" "F.Mask" "F.Paste")
			(net "SVID_PVDDCR_CPU1_P1_SVTO_R")
		)
		(pad "24" smd rect
			(at 2.199894 2.875026 270)
			(size 0.1778 0.6604)
			(layers "F.Cu" "F.Mask" "F.Paste")
			(net "SVID_PVDDCR_CPU1_P1_SVTI_R")
		)
		(pad "25" smd rect
			(at 2.875026 2.199894 180)
			(size 0.1778 0.6604)
			(layers "F.Cu" "F.Mask" "F.Paste")
			(net "VSENSE_PVDDCR_CPU1_P1_VSEN0")
		)
		(pad "26" smd rect
			(at 2.875026 1.800098 180)
			(size 0.1778 0.6604)
			(layers "F.Cu" "F.Mask" "F.Paste")
			(net "VSENSE_VSS_SENSE_C_P1")
		)
		(pad "27" smd rect
			(at 2.875026 1.400048 180)
			(size 0.1778 0.6604)
			(layers "F.Cu" "F.Mask" "F.Paste")
			(net "PVDDCR_CPU1_P1_IMON1")
		)
		(pad "28" smd rect
			(at 2.875026 0.999998 180)
			(size 0.1778 0.6604)
			(layers "F.Cu" "F.Mask" "F.Paste")
			(net "PVDDCR_CPU1_P1_IMON2")
		)
		(pad "29" smd rect
			(at 2.875026 0.599948 180)
			(size 0.1778 0.6604)
			(layers "F.Cu" "F.Mask" "F.Paste")
			(net "PVDDCR_CPU1_P1_IMON3")
		)
		(pad "30" smd rect
			(at 2.875026 0.199898 180)
			(size 0.1778 0.6604)
			(layers "F.Cu" "F.Mask" "F.Paste")
			(net "PVDDCR_CPU1_P1_IMON4")
		)
		(pad "31" smd rect
			(at 2.875026 -0.199898 180)
			(size 0.1778 0.6604)
			(layers "F.Cu" "F.Mask" "F.Paste")
			(net "PVDDCR_CPU1_P1_IMON5")
		)
		(pad "32" smd rect
			(at 2.875026 -0.599948 180)
			(size 0.1778 0.6604)
			(layers "F.Cu" "F.Mask" "F.Paste")
			(net "PVDDCR_CPU1_P1_IMON6")
		)
		(pad "33" smd rect
			(at 2.875026 -0.999998 180)
			(size 0.1778 0.6604)
			(layers "F.Cu" "F.Mask" "F.Paste")
			(net "NC_PVDDCR_CPU1_P1_IMON7")
		)
		(pad "34" smd rect
			(at 2.875026 -1.400048 180)
			(size 0.1778 0.6604)
			(layers "F.Cu" "F.Mask" "F.Paste")
			(net "NC_PVDDCR_CPU1_P1_IMON8")
		)
		(pad "35" smd rect
			(at 2.875026 -1.800098 180)
			(size 0.1778 0.6604)
			(layers "F.Cu" "F.Mask" "F.Paste")
			(net "PVDDIO_P1_IMON4")
		)
		(pad "36" smd rect
			(at 2.875026 -2.199894 180)
			(size 0.1778 0.6604)
			(layers "F.Cu" "F.Mask" "F.Paste")
			(net "PVDDIO_P1_IMON3")
		)
		(pad "37" smd rect
			(at 2.199894 -2.875026 270)
			(size 0.1778 0.6604)
			(layers "F.Cu" "F.Mask" "F.Paste")
			(net "PVDDIO_P1_IMON2")
		)
		(pad "38" smd rect
			(at 1.800098 -2.875026 270)
			(size 0.1778 0.6604)
			(layers "F.Cu" "F.Mask" "F.Paste")
			(net "PVDDIO_P1_IMON1")
		)
		(pad "39" smd rect
			(at 1.400048 -2.875026 270)
			(size 0.1778 0.6604)
			(layers "F.Cu" "F.Mask" "F.Paste")
			(net "VSENSE_VSS_SENSE_B_P1")
		)
		(pad "40" smd rect
			(at 0.999998 -2.875026 270)
			(size 0.1778 0.6604)
			(layers "F.Cu" "F.Mask" "F.Paste")
			(net "VSENSE_PVDDIO_P1_VSEN1")
		)
		(pad "41" smd rect
			(at 0.599948 -2.875026 270)
			(size 0.1778 0.6604)
			(layers "F.Cu" "F.Mask" "F.Paste")
			(net "PVDDCR_CPU1_P1_OCP_N_R")
		)
		(pad "42" smd rect
			(at 0.199898 -2.875026 270)
			(size 0.1778 0.6604)
			(layers "F.Cu" "F.Mask" "F.Paste")
			(net "PVDDCR_CPU1_P1_EN1_ADDR_CFG")
		)
	)
)
